# T6G (Grand Teton) — schematic netlist excerpt (pin names and nets, part order shuffled) for the footprints in the layout excerpt that follows; sources: Cadence DE-HDL packaged netlist, KiCad conversion of 04192023_DAF0TMB3IC0_F0TG_MB_C_brd_V02_OCP.brd

C1323  Q_CAP  0.1UF 25V 10% X7R  pkg 0402  page 148 : A = P1V8_AUX ; B = GND
PC206  Q_CAP  560PF 50V 10% EMPTY  pkg C0402  page 219 : A = SW_PVDDCR_CPU1_P1_SW3 ; B = SW_PVDDCR_CPU1_P1_SW3_RC
C735  Q_CAP_DIFFBUS  DIFF BUS_0.22UF 6.3V 20% X6S  pkg C0201  page 66 : \1\ = P5E_CPU1_P1_TX_C_DP<3> ; \2\ = P5E_CPU1_P1_TX_DP<3>

(kicad_pcb
	(version 20260206)
	(generator "pcbnew")
	(generator_version "10.0")
	(general
		(thickness 1.6)
		(legacy_teardrops no)
	)
	(paper "A4")
	(title_block
		(title "04192023_DAF0TMB3IC0_F0TG_MB_C_brd_V02_OCP.brd")
		(comment 1 "Grand Teton / footprints 1734-1736 of 8354")
	)
	(layers
		(0 "F.Cu" signal "TOP")
		(4 "In1.Cu" signal "GND")
		(6 "In2.Cu" signal "IN1")
		(8 "In3.Cu" signal "GND1")
		(10 "In4.Cu" signal "IN2")
		(12 "In5.Cu" signal "GND2")
		(14 "In6.Cu" signal "IN3")
		(16 "In7.Cu" signal "GND3")
		(18 "In8.Cu" signal "VCC")
		(20 "In9.Cu" signal "VCC1")
		(22 "In10.Cu" signal "GND4")
		(24 "In11.Cu" signal "IN4")
		(26 "In12.Cu" signal "GND5")
		(28 "In13.Cu" signal "IN5")
		(30 "In14.Cu" signal "GND6")
		(32 "In15.Cu" signal "IN6")
		(34 "In16.Cu" signal "GND7")
		(2 "B.Cu" signal "BOTTOM")
		(9 "F.Adhes" user "F.Adhesive")
		(11 "B.Adhes" user "B.Adhesive")
		(13 "F.Paste" user "Package Geometry/Pastemask Top")
		(15 "B.Paste" user "Package Geometry/Pastemask Bottom")
		(5 "F.SilkS" user "Ref Des/Silkscreen Top")
		(7 "B.SilkS" user "Ref Des/Silkscreen Bottom")
		(1 "F.Mask" user "Board Geometry/Soldermask Top")
		(3 "B.Mask" user "Board Geometry/Soldermask Bottom")
		(17 "Dwgs.User" user "User.Drawings")
		(19 "Cmts.User" user "User.Comments")
		(21 "Eco1.User" user "User.Eco1")
		(23 "Eco2.User" user "User.Eco2")
		(25 "Edge.Cuts" user "Board Geometry/Outline")
		(27 "Margin" user)
		(31 "F.CrtYd" user "Package Geometry/Place Bound Top")
		(29 "B.CrtYd" user "Package Geometry/Place Bound Bottom")
		(35 "F.Fab" user "Ref Des/Assembly Top")
		(33 "B.Fab" user "Ref Des/Assembly Bottom")
	)
	(footprint ""
		(layer "F.Cu")
		(at 149.401276 -44.8437 90)
		(property "Reference" "C1323"
			(at 0 0 90)
			(layer "F.SilkS")
			(hide yes)
			(effects
				(font
					(size 1.27 1.27)
				)
			)
		)
		(property "Value" ""
			(at 0 0 90)
			(layer "F.Fab")
			(effects
				(font
					(size 1.27 1.27)
				)
			)
		)
		(duplicate_pad_numbers_are_jumpers no)
		(fp_line
			(start 0.7874 -0.4064)
			(end 0.7874 0.4064)
			(stroke
				(width 0.1524)
				(type default)
			)
			(layer "F.SilkS")
		)
		(fp_line
			(start -0.7874 -0.4064)
			(end 0.7874 -0.4064)
			(stroke
				(width 0.1524)
				(type default)
			)
			(layer "F.SilkS")
		)
		(fp_line
			(start 0.7874 0.4064)
			(end -0.7874 0.4064)
			(stroke
				(width 0.1524)
				(type default)
			)
			(layer "F.SilkS")
		)
		(fp_line
			(start -0.7874 0.4064)
			(end -0.7874 -0.4064)
			(stroke
				(width 0.1524)
				(type default)
			)
			(layer "F.SilkS")
		)
		(fp_line
			(start -0.12065 -0.305054)
			(end -0.12065 -0.2794)
			(stroke
				(width 0.1)
				(type default)
			)
			(layer "F.Fab")
		)
		(fp_line
			(start -0.67945 -0.305054)
			(end -0.12065 -0.305054)
			(stroke
				(width 0.1)
				(type default)
			)
			(layer "F.Fab")
		)
		(fp_line
			(start 0.67945 -0.3048)
			(end 0.67945 0.3048)
			(stroke
				(width 0.1)
				(type default)
			)
			(layer "F.Fab")
		)
		(fp_line
			(start 0.12065 -0.3048)
			(end 0.67945 -0.3048)
			(stroke
				(width 0.1)
				(type default)
			)
			(layer "F.Fab")
		)
		(fp_line
			(start 0.12065 -0.2794)
			(end 0.12065 -0.3048)
			(stroke
				(width 0.1)
				(type default)
			)
			(layer "F.Fab")
		)
		(fp_line
			(start -0.12065 -0.2794)
			(end 0.12065 -0.2794)
			(stroke
				(width 0.1)
				(type default)
			)
			(layer "F.Fab")
		)
		(fp_line
			(start 0.120396 0.2794)
			(end -0.12065 0.2794)
			(stroke
				(width 0.1)
				(type default)
			)
			(layer "F.Fab")
		)
		(fp_line
			(start -0.12065 0.2794)
			(end -0.12065 0.3048)
			(stroke
				(width 0.1)
				(type default)
			)
			(layer "F.Fab")
		)
		(fp_line
			(start 0.67945 0.3048)
			(end 0.120396 0.3048)
			(stroke
				(width 0.1)
				(type default)
			)
			(layer "F.Fab")
		)
		(fp_line
			(start 0.120396 0.3048)
			(end 0.120396 0.2794)
			(stroke
				(width 0.1)
				(type default)
			)
			(layer "F.Fab")
		)
		(fp_line
			(start -0.12065 0.3048)
			(end -0.67945 0.3048)
			(stroke
				(width 0.1)
				(type default)
			)
			(layer "F.Fab")
		)
		(fp_line
			(start -0.67945 0.3048)
			(end -0.67945 -0.305054)
			(stroke
				(width 0.1)
				(type default)
			)
			(layer "F.Fab")
		)
		(pad "1" smd circle
			(at -0.40005 0 90)
			(size 0 0)
			(layers "F.Cu" "F.Mask" "F.Paste")
			(net "P1V8_AUX")
		)
		(pad "2" smd circle
			(at 0.40005 0 90)
			(size 0 0)
			(layers "F.Cu" "F.Mask" "F.Paste")
			(net "GND")
		)
	)
	(footprint ""
		(layer "F.Cu")
		(at 77.219302 -370.57203 -90)
		(property "Reference" "C735"
			(at 0 0 270)
			(layer "F.SilkS")
			(hide yes)
			(effects
				(font
					(size 1.27 1.27)
				)
			)
		)
		(property "Value" ""
			(at 0 0 270)
			(layer "F.Fab")
			(effects
				(font
					(size 1.27 1.27)
				)
			)
		)
		(duplicate_pad_numbers_are_jumpers no)
		(fp_line
			(start -0.299974 0.150114)
			(end -0.299974 -0.150114)
			(stroke
				(width 0.1)
				(type default)
			)
			(layer "F.Fab")
		)
		(fp_line
			(start 0.299974 0.150114)
			(end -0.299974 0.150114)
			(stroke
				(width 0.1)
				(type default)
			)
			(layer "F.Fab")
		)
		(fp_line
			(start -0.299974 -0.150114)
			(end 0.299974 -0.150114)
			(stroke
				(width 0.1)
				(type default)
			)
			(layer "F.Fab")
		)
		(fp_line
			(start 0.299974 -0.150114)
			(end 0.299974 0.150114)
			(stroke
				(width 0.1)
				(type default)
			)
			(layer "F.Fab")
		)
		(pad "1" smd rect
			(at -0.2667 0 270)
			(size 0.3048 0.381)
			(layers "F.Cu" "F.Mask" "F.Paste")
			(net "P5E_CPU1_P1_TX_C_DP<3>")
		)
		(pad "2" smd rect
			(at 0.2667 0 270)
			(size 0.3048 0.381)
			(layers "F.Cu" "F.Mask" "F.Paste")
			(net "P5E_CPU1_P1_TX_DP<3>")
		)
	)
	(footprint ""
		(layer "F.Cu")
		(at 66.715132 -331.99578 180)
		(property "Reference" "PC206"
			(at 0 0 180)
			(layer "F.SilkS")
			(hide yes)
			(effects
				(font
					(size 1.27 1.27)
				)
			)
		)
		(property "Value" ""
			(at 0 0 180)
			(layer "F.Fab")
			(effects
				(font
					(size 1.27 1.27)
				)
			)
		)
		(duplicate_pad_numbers_are_jumpers no)
		(fp_line
			(start 0.7874 0.4064)
			(end -0.7874 0.4064)
			(stroke
				(width 0.1524)
				(type default)
			)
			(layer "F.SilkS")
		)
		(fp_line
			(start 0.7874 -0.4064)
			(end 0.7874 0.4064)
			(stroke
				(width 0.1524)
				(type default)
			)
			(layer "F.SilkS")
		)
		(fp_line
			(start -0.7874 0.4064)
			(end -0.7874 -0.4064)
			(stroke
				(width 0.1524)
				(type default)
			)
			(layer "F.SilkS")
		)
		(fp_line
			(start -0.7874 -0.4064)
			(end 0.7874 -0.4064)
			(stroke
				(width 0.1524)
				(type default)
			)
			(layer "F.SilkS")
		)
		(fp_line
			(start 0.67945 0.3048)
			(end 0.120396 0.3048)
			(stroke
				(width 0.1)
				(type default)
			)
			(layer "F.Fab")
		)
		(fp_line
			(start 0.67945 -0.3048)
			(end 0.67945 0.3048)
			(stroke
				(width 0.1)
				(type default)
			)
			(layer "F.Fab")
		)
		(fp_line
			(start 0.12065 -0.2794)
			(end 0.12065 -0.3048)
			(stroke
				(width 0.1)
				(type default)
			)
			(layer "F.Fab")
		)
		(fp_line
			(start 0.12065 -0.3048)
			(end 0.67945 -0.3048)
			(stroke
				(width 0.1)
				(type default)
			)
			(layer "F.Fab")
		)
		(fp_line
			(start 0.120396 0.3048)
			(end 0.120396 0.2794)
			(stroke
				(width 0.1)
				(type default)
			)
			(layer "F.Fab")
		)
		(fp_line
			(start 0.120396 0.2794)
			(end -0.12065 0.2794)
			(stroke
				(width 0.1)
				(type default)
			)
			(layer "F.Fab")
		)
		(fp_line
			(start -0.12065 0.3048)
			(end -0.67945 0.3048)
			(stroke
				(width 0.1)
				(type default)
			)
			(layer "F.Fab")
		)
		(fp_line
			(start -0.12065 0.2794)
			(end -0.12065 0.3048)
			(stroke
				(width 0.1)
				(type default)
			)
			(layer "F.Fab")
		)
		(fp_line
			(start -0.12065 -0.2794)
			(end 0.12065 -0.2794)
			(stroke
				(width 0.1)
				(type default)
			)
			(layer "F.Fab")
		)
		(fp_line
			(start -0.12065 -0.305054)
			(end -0.12065 -0.2794)
			(stroke
				(width 0.1)
				(type default)
			)
			(layer "F.Fab")
		)
		(fp_line
			(start -0.67945 0.3048)
			(end -0.67945 -0.305054)
			(stroke
				(width 0.1)
				(type default)
			)
			(layer "F.Fab")
		)
		(fp_line
			(start -0.67945 -0.305054)
			(end -0.12065 -0.305054)
			(stroke
				(width 0.1)
				(type default)
			)
			(layer "F.Fab")
		)
		(pad "1" smd circle
			(at -0.40005 0 180)
			(size 0 0)
			(layers "F.Cu" "F.Mask" "F.Paste")
			(net "SW_PVDDCR_CPU1_P1_SW3")
		)
		(pad "2" smd circle
			(at 0.40005 0 180)
			(size 0 0)
			(layers "F.Cu" "F.Mask" "F.Paste")
			(net "SW_PVDDCR_CPU1_P1_SW3_RC")
		)
	)
)
